# T6G (Grand Teton) — schematic netlist excerpt (pin names and nets, part order shuffled) for the footprints in the layout excerpt that follows; sources: Cadence DE-HDL packaged netlist, KiCad conversion of 04192023_DAF0TMB3IC0_F0TG_MB_C_brd_V02_OCP.brd

PU34  RAA229620GNPHA0  RAA229620GNP#HA0 IC  pkg QFN48_TH_0-4_6X6XH  page 217
  PWM0  = PVDDIO_P1_PWM1
  PWM1  = PVDDIO_P1_PWM2
  PWM2  = PVDDIO_P1_PWM3
  PWM3  = PVDDIO_P1_PWM4
  PWM4  = NC_PVDDCR_CPU1_P1_PWM8
  PWM5  = NC_PVDDCR_CPU1_P1_PWM7
  PWM6  = PVDDCR_CPU1_P1_PWM6
  PWM7  = PVDDCR_CPU1_P1_PWM5
  PWM8  = PVDDCR_CPU1_P1_PWM4
  PWM9  = PVDDCR_CPU1_P1_PWM3
  PWM10  = PVDDCR_CPU1_P1_PWM2
  PWM11  = PVDDCR_CPU1_P1_PWM1
  PMSDA  = SMB_DIO_PVDDCR_CPU1_P1_R
  PMSCL  = SMB_CLK_PVDDCR_CPU1_P1_R
  NPMALERT  = PVDDCR_CPU1_P1_SMB_ALERT_R
  PG0  = PWRGD_PVDDCR_CPU1_P1_R
  EN0  = PVDDCR_CPU1_P1_EN_R
  RESET_L  = PVDDCR_CPU1_P1_RESET_N_R
  VDDIO  = PVDD18_S5_P1
  PG1  = PWRGD_PVDDIO_P1_R
  SVD  = SVID_PVDDCR_CPU1_P1_SVD_R1
  SVC  = SVID_PVDDCR_CPU1_P1_SVC_R1
  SVTO  = SVID_PVDDCR_CPU1_P1_SVTO_R
  SVTI  = SVID_PVDDCR_CPU1_P1_SVTI_R
  VSEN0  = VSENSE_PVDDCR_CPU1_P1_VSEN0
  RGND0  = VSENSE_VSS_SENSE_C_P1
  CS11  = PVDDCR_CPU1_P1_IMON1
  CS10  = PVDDCR_CPU1_P1_IMON2
  CS9  = PVDDCR_CPU1_P1_IMON3
  CS8  = PVDDCR_CPU1_P1_IMON4
  CS7  = PVDDCR_CPU1_P1_IMON5
  CS6  = PVDDCR_CPU1_P1_IMON6
  CS5  = NC_PVDDCR_CPU1_P1_IMON7
  CS4  = NC_PVDDCR_CPU1_P1_IMON8
  CS3  = PVDDIO_P1_IMON4
  CS2  = PVDDIO_P1_IMON3
  CS1  = PVDDIO_P1_IMON2
  CS0  = PVDDIO_P1_IMON1
  RGND1  = VSENSE_VSS_SENSE_B_P1
  VSEN1  = VSENSE_PVDDIO_P1_VSEN1
  OCP_L  = PVDDCR_CPU1_P1_OCP_N_R
  \en1||addr_cfg\  = PVDDCR_CPU1_P1_EN1_ADDR_CFG
  TEMP1  = PVDDIO_P1_TEMP1
  TEMP0  = PVDDCR_CPU1_P1_TEMP0
  \vmon||iinsen\  = PVDDCR_CPU1_P1_VMON
  VINSEN  = PVDDCR_CPU1_P1_VINSEN
  VCC  = PVDDCR_CPU1_P1_VCC
  VCCS  = PVDDCR_CPU1_P1_VCCS
  TH_GND  = GND

(kicad_pcb
	(version 20260206)
	(generator "pcbnew")
	(generator_version "10.0")
	(general
		(thickness 1.6)
		(legacy_teardrops no)
	)
	(paper "A4")
	(title_block
		(title "04192023_DAF0TMB3IC0_F0TG_MB_C_brd_V02_OCP.brd")
		(comment 1 "Grand Teton / footprint 1342 of 8354 (PU34), pads 43-49 of 49")
	)
	(layers
		(0 "F.Cu" signal "TOP")
		(4 "In1.Cu" signal "GND")
		(6 "In2.Cu" signal "IN1")
		(8 "In3.Cu" signal "GND1")
		(10 "In4.Cu" signal "IN2")
		(12 "In5.Cu" signal "GND2")
		(14 "In6.Cu" signal "IN3")
		(16 "In7.Cu" signal "GND3")
		(18 "In8.Cu" signal "VCC")
		(20 "In9.Cu" signal "VCC1")
		(22 "In10.Cu" signal "GND4")
		(24 "In11.Cu" signal "IN4")
		(26 "In12.Cu" signal "GND5")
		(28 "In13.Cu" signal "IN5")
		(30 "In14.Cu" signal "GND6")
		(32 "In15.Cu" signal "IN6")
		(34 "In16.Cu" signal "GND7")
		(2 "B.Cu" signal "BOTTOM")
		(9 "F.Adhes" user "F.Adhesive")
		(11 "B.Adhes" user "B.Adhesive")
		(13 "F.Paste" user "Package Geometry/Pastemask Top")
		(15 "B.Paste" user "Package Geometry/Pastemask Bottom")
		(5 "F.SilkS" user "Ref Des/Silkscreen Top")
		(7 "B.SilkS" user "Ref Des/Silkscreen Bottom")
		(1 "F.Mask" user "Board Geometry/Soldermask Top")
		(3 "B.Mask" user "Board Geometry/Soldermask Bottom")
		(17 "Dwgs.User" user "User.Drawings")
		(19 "Cmts.User" user "User.Comments")
		(21 "Eco1.User" user "User.Eco1")
		(23 "Eco2.User" user "User.Eco2")
		(25 "Edge.Cuts" user "Board Geometry/Outline")
		(27 "Margin" user)
		(31 "F.CrtYd" user "Package Geometry/Place Bound Top")
		(29 "B.CrtYd" user "Package Geometry/Place Bound Bottom")
		(35 "F.Fab" user "Ref Des/Assembly Top")
		(33 "B.Fab" user "Ref Des/Assembly Bottom")
	)
	(footprint ""
		(layer "F.Cu")
		(at 30.48 -364.109 -90)
		(property "Reference" "PU34"
			(at 3.80873 0.935736 0)
			(unlocked yes)
			(layer "F.SilkS")
			(effects
				(font
					(size 0.7874 0.5842)
					(thickness 0.1524)
				)
			)
		)
		(property "Value" ""
			(at 0 0 270)
			(layer "F.Fab")
			(effects
				(font
					(size 1.27 1.27)
				)
			)
		)
		(duplicate_pad_numbers_are_jumpers no)
		(pad "43" smd rect
			(at -0.199898 -2.875026 270)
			(size 0.1778 0.6604)
			(layers "F.Cu" "F.Mask" "F.Paste")
			(net "PVDDIO_P1_TEMP1")
		)
		(pad "44" smd rect
			(at -0.599948 -2.875026 270)
			(size 0.1778 0.6604)
			(layers "F.Cu" "F.Mask" "F.Paste")
			(net "PVDDCR_CPU1_P1_TEMP0")
		)
		(pad "45" smd rect
			(at -0.999998 -2.875026 270)
			(size 0.1778 0.6604)
			(layers "F.Cu" "F.Mask" "F.Paste")
			(net "PVDDCR_CPU1_P1_VMON")
		)
		(pad "46" smd rect
			(at -1.400048 -2.875026 270)
			(size 0.1778 0.6604)
			(layers "F.Cu" "F.Mask" "F.Paste")
			(net "PVDDCR_CPU1_P1_VINSEN")
		)
		(pad "47" smd rect
			(at -1.800098 -2.875026 270)
			(size 0.1778 0.6604)
			(layers "F.Cu" "F.Mask" "F.Paste")
			(net "PVDDCR_CPU1_P1_VCC")
		)
		(pad "48" smd rect
			(at -2.199894 -2.875026 270)
			(size 0.1778 0.6604)
			(layers "F.Cu" "F.Mask" "F.Paste")
			(net "PVDDCR_CPU1_P1_VCCS")
		)
		(pad "TH" smd rect
			(at 0 0 270)
			(size 4.4196 4.4196)
			(layers "F.Cu" "F.Mask" "F.Paste")
			(net "GND")
		)
	)
)
